(kicad_pcb
	(version 20260206)
	(generator "pcbnew")
	(generator_version "10.0")
	(general
		(thickness 1.6)
		(legacy_teardrops no)
	)
	(paper "A4")
	(title_block
		(title "04192023_DAF0TMB3IC0_F0TG_MB_C_brd_V02_OCP.brd")
		(comment 1 "Grand Teton / footprints 6698-6705 of 8354")
	)
	(layers
		(0 "F.Cu" signal "TOP")
		(4 "In1.Cu" signal "GND")
		(6 "In2.Cu" signal "IN1")
		(8 "In3.Cu" signal "GND1")
		(10 "In4.Cu" signal "IN2")
		(12 "In5.Cu" signal "GND2")
		(14 "In6.Cu" signal "IN3")
		(16 "In7.Cu" signal "GND3")
		(18 "In8.Cu" signal "VCC")
		(20 "In9.Cu" signal "VCC1")
		(22 "In10.Cu" signal "GND4")
		(24 "In11.Cu" signal "IN4")
		(26 "In12.Cu" signal "GND5")
		(28 "In13.Cu" signal "IN5")
		(30 "In14.Cu" signal "GND6")
		(32 "In15.Cu" signal "IN6")
		(34 "In16.Cu" signal "GND7")
		(2 "B.Cu" signal "BOTTOM")
		(9 "F.Adhes" user "F.Adhesive")
		(11 "B.Adhes" user "B.Adhesive")
		(13 "F.Paste" user "Package Geometry/Pastemask Top")
		(15 "B.Paste" user "Package Geometry/Pastemask Bottom")
		(5 "F.SilkS" user "Ref Des/Silkscreen Top")
		(7 "B.SilkS" user "Ref Des/Silkscreen Bottom")
		(1 "F.Mask" user "Board Geometry/Soldermask Top")
		(3 "B.Mask" user "Board Geometry/Soldermask Bottom")
		(17 "Dwgs.User" user "User.Drawings")
		(19 "Cmts.User" user "User.Comments")
		(21 "Eco1.User" user "User.Eco1")
		(23 "Eco2.User" user "User.Eco2")
		(25 "Edge.Cuts" user "Board Geometry/Outline")
		(27 "Margin" user)
		(31 "F.CrtYd" user "Package Geometry/Place Bound Top")
		(29 "B.CrtYd" user "Package Geometry/Place Bound Bottom")
		(35 "F.Fab" user "Ref Des/Assembly Top")
		(33 "B.Fab" user "Ref Des/Assembly Bottom")
	)
	(footprint ""
		(layer "B.Cu")
		(at 345.50604 -395.148562 90)
		(property "Reference" "C602"
			(at 0 0 90)
			(layer "B.SilkS")
			(hide yes)
			(effects
				(font
					(size 1.27 1.27)
				)
				(justify mirror)
			)
		)
		(property "Value" ""
			(at 0 0 90)
			(layer "B.Fab")
			(effects
				(font
					(size 1.27 1.27)
				)
				(justify mirror)
			)
		)
		(duplicate_pad_numbers_are_jumpers no)
		(fp_line
			(start 0.299974 -0.150114)
			(end -0.299974 -0.150114)
			(stroke
				(width 0.1)
				(type default)
			)
			(layer "B.Fab")
		)
		(fp_line
			(start -0.299974 -0.150114)
			(end -0.299974 0.150114)
			(stroke
				(width 0.1)
				(type default)
			)
			(layer "B.Fab")
		)
		(fp_line
			(start 0.299974 0.150114)
			(end 0.299974 -0.150114)
			(stroke
				(width 0.1)
				(type default)
			)
			(layer "B.Fab")
		)
		(fp_line
			(start -0.299974 0.150114)
			(end 0.299974 0.150114)
			(stroke
				(width 0.1)
				(type default)
			)
			(layer "B.Fab")
		)
		(pad "1" smd rect
			(at 0.2667 0 270)
			(size 0.3048 0.381)
			(layers "B.Cu" "B.Mask" "B.Paste")
			(net "P1V8_CPU0_RT1_1A")
		)
		(pad "2" smd rect
			(at -0.2667 0 270)
			(size 0.3048 0.381)
			(layers "B.Cu" "B.Mask" "B.Paste")
			(net "GND")
		)
	)
	(footprint ""
		(layer "B.Cu")
		(at 67.958462 -167.869362 90)
		(property "Reference" "PR422"
			(at 0 0 90)
			(layer "B.SilkS")
			(hide yes)
			(effects
				(font
					(size 1.27 1.27)
				)
				(justify mirror)
			)
		)
		(property "Value" ""
			(at 0 0 90)
			(layer "B.Fab")
			(effects
				(font
					(size 1.27 1.27)
				)
				(justify mirror)
			)
		)
		(duplicate_pad_numbers_are_jumpers no)
		(fp_line
			(start 0.7874 -0.4064)
			(end -0.7874 -0.4064)
			(stroke
				(width 0.1524)
				(type default)
			)
			(layer "B.SilkS")
		)
		(fp_line
			(start -0.7874 -0.4064)
			(end -0.7874 0.4064)
			(stroke
				(width 0.1524)
				(type default)
			)
			(layer "B.SilkS")
		)
		(fp_line
			(start 0.7874 0.4064)
			(end 0.7874 -0.4064)
			(stroke
				(width 0.1524)
				(type default)
			)
			(layer "B.SilkS")
		)
		(fp_line
			(start -0.7874 0.4064)
			(end 0.7874 0.4064)
			(stroke
				(width 0.1524)
				(type default)
			)
			(layer "B.SilkS")
		)
		(fp_line
			(start 0.67945 -0.305054)
			(end 0.12065 -0.305054)
			(stroke
				(width 0.1)
				(type default)
			)
			(layer "B.Fab")
		)
		(fp_line
			(start 0.12065 -0.305054)
			(end 0.12065 -0.2794)
			(stroke
				(width 0.1)
				(type default)
			)
			(layer "B.Fab")
		)
		(fp_line
			(start -0.12065 -0.3048)
			(end -0.67945 -0.3048)
			(stroke
				(width 0.1)
				(type default)
			)
			(layer "B.Fab")
		)
		(fp_line
			(start -0.67945 -0.3048)
			(end -0.67945 0.3048)
			(stroke
				(width 0.1)
				(type default)
			)
			(layer "B.Fab")
		)
		(fp_line
			(start 0.12065 -0.2794)
			(end -0.12065 -0.2794)
			(stroke
				(width 0.1)
				(type default)
			)
			(layer "B.Fab")
		)
		(fp_line
			(start -0.12065 -0.2794)
			(end -0.12065 -0.3048)
			(stroke
				(width 0.1)
				(type default)
			)
			(layer "B.Fab")
		)
		(fp_line
			(start 0.12065 0.2794)
			(end 0.12065 0.3048)
			(stroke
				(width 0.1)
				(type default)
			)
			(layer "B.Fab")
		)
		(fp_line
			(start -0.120396 0.2794)
			(end 0.12065 0.2794)
			(stroke
				(width 0.1)
				(type default)
			)
			(layer "B.Fab")
		)
		(fp_line
			(start 0.67945 0.3048)
			(end 0.67945 -0.305054)
			(stroke
				(width 0.1)
				(type default)
			)
			(layer "B.Fab")
		)
		(fp_line
			(start 0.12065 0.3048)
			(end 0.67945 0.3048)
			(stroke
				(width 0.1)
				(type default)
			)
			(layer "B.Fab")
		)
		(fp_line
			(start -0.120396 0.3048)
			(end -0.120396 0.2794)
			(stroke
				(width 0.1)
				(type default)
			)
			(layer "B.Fab")
		)
		(fp_line
			(start -0.67945 0.3048)
			(end -0.120396 0.3048)
			(stroke
				(width 0.1)
				(type default)
			)
			(layer "B.Fab")
		)
		(pad "1" smd circle
			(at 0.40005 0 270)
			(size 0 0)
			(layers "B.Cu" "B.Mask" "B.Paste")
			(net "PVDDCR_CPU0_P1_PVCC")
		)
		(pad "2" smd circle
			(at -0.40005 0 270)
			(size 0 0)
			(layers "B.Cu" "B.Mask" "B.Paste")
			(net "PVDDCR_CPU0_P1_VCC6")
		)
	)
	(footprint ""
		(layer "B.Cu")
		(at 18.039588 -399.209006)
		(property "Reference" "PC6616_1"
			(at 0 0 0)
			(layer "B.SilkS")
			(hide yes)
			(effects
				(font
					(size 1.27 1.27)
				)
				(justify mirror)
			)
		)
		(property "Value" ""
			(at 0 0 0)
			(layer "B.Fab")
			(effects
				(font
					(size 1.27 1.27)
				)
				(justify mirror)
			)
		)
		(duplicate_pad_numbers_are_jumpers no)
		(fp_line
			(start -1.524 -0.762)
			(end -1.524 0.762)
			(stroke
				(width 0.1524)
				(type default)
			)
			(layer "B.SilkS")
		)
		(fp_line
			(start -1.524 0.762)
			(end 1.524 0.762)
			(stroke
				(width 0.1524)
				(type default)
			)
			(layer "B.SilkS")
		)
		(fp_line
			(start 1.524 -0.762)
			(end -1.524 -0.762)
			(stroke
				(width 0.1524)
				(type default)
			)
			(layer "B.SilkS")
		)
		(fp_line
			(start 1.524 0.762)
			(end 1.524 -0.762)
			(stroke
				(width 0.1524)
				(type default)
			)
			(layer "B.SilkS")
		)
		(fp_line
			(start -1.1049 -0.724916)
			(end 1.1049 -0.724916)
			(stroke
				(width 0.1)
				(type default)
			)
			(layer "B.Fab")
		)
		(fp_line
			(start -1.1049 0.724916)
			(end -1.1049 -0.724916)
			(stroke
				(width 0.1)
				(type default)
			)
			(layer "B.Fab")
		)
		(fp_line
			(start 1.1049 -0.724916)
			(end 1.1049 0.724916)
			(stroke
				(width 0.1)
				(type default)
			)
			(layer "B.Fab")
		)
		(fp_line
			(start 1.1049 0.724916)
			(end -1.1049 0.724916)
			(stroke
				(width 0.1)
				(type default)
			)
			(layer "B.Fab")
		)
		(pad "1" smd rect
			(at 0.889 0)
			(size 1.016 1.27)
			(layers "B.Cu" "B.Mask" "B.Paste")
			(net "SW_P12V_AUX_P0V9_RETIMER_CPU1_FLT")
		)
		(pad "2" smd rect
			(at -0.889 0)
			(size 1.016 1.27)
			(layers "B.Cu" "B.Mask" "B.Paste")
			(net "GND")
		)
	)
	(footprint ""
		(layer "B.Cu")
		(at 128.172972 -41.947592 -90)
		(property "Reference" "C6077"
			(at 0 0 90)
			(layer "B.SilkS")
			(hide yes)
			(effects
				(font
					(size 1.27 1.27)
				)
				(justify mirror)
			)
		)
		(property "Value" ""
			(at 0 0 90)
			(layer "B.Fab")
			(effects
				(font
					(size 1.27 1.27)
				)
				(justify mirror)
			)
		)
		(duplicate_pad_numbers_are_jumpers no)
		(fp_line
			(start -0.7874 0.4064)
			(end 0.7874 0.4064)
			(stroke
				(width 0.1524)
				(type default)
			)
			(layer "B.SilkS")
		)
		(fp_line
			(start 0.7874 0.4064)
			(end 0.7874 -0.4064)
			(stroke
				(width 0.1524)
				(type default)
			)
			(layer "B.SilkS")
		)
		(fp_line
			(start -0.7874 -0.4064)
			(end -0.7874 0.4064)
			(stroke
				(width 0.1524)
				(type default)
			)
			(layer "B.SilkS")
		)
		(fp_line
			(start 0.7874 -0.4064)
			(end -0.7874 -0.4064)
			(stroke
				(width 0.1524)
				(type default)
			)
			(layer "B.SilkS")
		)
		(fp_line
			(start -0.67945 0.3048)
			(end -0.120396 0.3048)
			(stroke
				(width 0.1)
				(type default)
			)
			(layer "B.Fab")
		)
		(fp_line
			(start -0.120396 0.3048)
			(end -0.120396 0.2794)
			(stroke
				(width 0.1)
				(type default)
			)
			(layer "B.Fab")
		)
		(fp_line
			(start 0.12065 0.3048)
			(end 0.67945 0.3048)
			(stroke
				(width 0.1)
				(type default)
			)
			(layer "B.Fab")
		)
		(fp_line
			(start 0.67945 0.3048)
			(end 0.67945 -0.305054)
			(stroke
				(width 0.1)
				(type default)
			)
			(layer "B.Fab")
		)
		(fp_line
			(start -0.120396 0.2794)
			(end 0.12065 0.2794)
			(stroke
				(width 0.1)
				(type default)
			)
			(layer "B.Fab")
		)
		(fp_line
			(start 0.12065 0.2794)
			(end 0.12065 0.3048)
			(stroke
				(width 0.1)
				(type default)
			)
			(layer "B.Fab")
		)
		(fp_line
			(start -0.12065 -0.2794)
			(end -0.12065 -0.3048)
			(stroke
				(width 0.1)
				(type default)
			)
			(layer "B.Fab")
		)
		(fp_line
			(start 0.12065 -0.2794)
			(end -0.12065 -0.2794)
			(stroke
				(width 0.1)
				(type default)
			)
			(layer "B.Fab")
		)
		(fp_line
			(start -0.67945 -0.3048)
			(end -0.67945 0.3048)
			(stroke
				(width 0.1)
				(type default)
			)
			(layer "B.Fab")
		)
		(fp_line
			(start -0.12065 -0.3048)
			(end -0.67945 -0.3048)
			(stroke
				(width 0.1)
				(type default)
			)
			(layer "B.Fab")
		)
		(fp_line
			(start 0.12065 -0.305054)
			(end 0.12065 -0.2794)
			(stroke
				(width 0.1)
				(type default)
			)
			(layer "B.Fab")
		)
		(fp_line
			(start 0.67945 -0.305054)
			(end 0.12065 -0.305054)
			(stroke
				(width 0.1)
				(type default)
			)
			(layer "B.Fab")
		)
		(pad "1" smd circle
			(at 0.40005 0 90)
			(size 0 0)
			(layers "B.Cu" "B.Mask" "B.Paste")
			(net "P1V2_AUX")
		)
		(pad "2" smd circle
			(at -0.40005 0 90)
			(size 0 0)
			(layers "B.Cu" "B.Mask" "B.Paste")
			(net "GND")
		)
	)
	(footprint ""
		(layer "B.Cu")
		(at 121.685812 -258.830318)
		(property "Reference" "C3916"
			(at 0 0 0)
			(layer "B.SilkS")
			(hide yes)
			(effects
				(font
					(size 1.27 1.27)
				)
				(justify mirror)
			)
		)
		(property "Value" ""
			(at 0 0 0)
			(layer "B.Fab")
			(effects
				(font
					(size 1.27 1.27)
				)
				(justify mirror)
			)
		)
		(duplicate_pad_numbers_are_jumpers no)
		(fp_line
			(start -0.7874 -0.4064)
			(end -0.7874 0.4064)
			(stroke
				(width 0.1524)
				(type default)
			)
			(layer "B.SilkS")
		)
		(fp_line
			(start -0.7874 0.4064)
			(end 0.7874 0.4064)
			(stroke
				(width 0.1524)
				(type default)
			)
			(layer "B.SilkS")
		)
		(fp_line
			(start 0.7874 -0.4064)
			(end -0.7874 -0.4064)
			(stroke
				(width 0.1524)
				(type default)
			)
			(layer "B.SilkS")
		)
		(fp_line
			(start 0.7874 0.4064)
			(end 0.7874 -0.4064)
			(stroke
				(width 0.1524)
				(type default)
			)
			(layer "B.SilkS")
		)
		(fp_line
			(start -0.67945 -0.3048)
			(end -0.67945 0.3048)
			(stroke
				(width 0.1)
				(type default)
			)
			(layer "B.Fab")
		)
		(fp_line
			(start -0.67945 0.3048)
			(end -0.120396 0.3048)
			(stroke
				(width 0.1)
				(type default)
			)
			(layer "B.Fab")
		)
		(fp_line
			(start -0.12065 -0.3048)
			(end -0.67945 -0.3048)
			(stroke
				(width 0.1)
				(type default)
			)
			(layer "B.Fab")
		)
		(fp_line
			(start -0.12065 -0.2794)
			(end -0.12065 -0.3048)
			(stroke
				(width 0.1)
				(type default)
			)
			(layer "B.Fab")
		)
		(fp_line
			(start -0.120396 0.2794)
			(end 0.12065 0.2794)
			(stroke
				(width 0.1)
				(type default)
			)
			(layer "B.Fab")
		)
		(fp_line
			(start -0.120396 0.3048)
			(end -0.120396 0.2794)
			(stroke
				(width 0.1)
				(type default)
			)
			(layer "B.Fab")
		)
		(fp_line
			(start 0.12065 -0.305054)
			(end 0.12065 -0.2794)
			(stroke
				(width 0.1)
				(type default)
			)
			(layer "B.Fab")
		)
		(fp_line
			(start 0.12065 -0.2794)
			(end -0.12065 -0.2794)
			(stroke
				(width 0.1)
				(type default)
			)
			(layer "B.Fab")
		)
		(fp_line
			(start 0.12065 0.2794)
			(end 0.12065 0.3048)
			(stroke
				(width 0.1)
				(type default)
			)
			(layer "B.Fab")
		)
		(fp_line
			(start 0.12065 0.3048)
			(end 0.67945 0.3048)
			(stroke
				(width 0.1)
				(type default)
			)
			(layer "B.Fab")
		)
		(fp_line
			(start 0.67945 -0.305054)
			(end 0.12065 -0.305054)
			(stroke
				(width 0.1)
				(type default)
			)
			(layer "B.Fab")
		)
		(fp_line
			(start 0.67945 0.3048)
			(end 0.67945 -0.305054)
			(stroke
				(width 0.1)
				(type default)
			)
			(layer "B.Fab")
		)
		(pad "1" smd circle
			(at 0.40005 0 180)
			(size 0 0)
			(layers "B.Cu" "B.Mask" "B.Paste")
			(net "PVDDCR_SOC_P1")
		)
		(pad "2" smd circle
			(at -0.40005 0 180)
			(size 0 0)
			(layers "B.Cu" "B.Mask" "B.Paste")
			(net "GND")
		)
	)
	(footprint ""
		(layer "B.Cu")
		(at 102.378764 -257.930396 180)
		(property "Reference" "C2110"
			(at 0 0 0)
			(layer "B.SilkS")
			(hide yes)
			(effects
				(font
					(size 1.27 1.27)
				)
				(justify mirror)
			)
		)
		(property "Value" ""
			(at 0 0 0)
			(layer "B.Fab")
			(effects
				(font
					(size 1.27 1.27)
				)
				(justify mirror)
			)
		)
		(duplicate_pad_numbers_are_jumpers no)
		(fp_line
			(start 0.7874 0.4064)
			(end 0.7874 -0.4064)
			(stroke
				(width 0.1524)
				(type default)
			)
			(layer "B.SilkS")
		)
		(fp_line
			(start 0.7874 -0.4064)
			(end -0.7874 -0.4064)
			(stroke
				(width 0.1524)
				(type default)
			)
			(layer "B.SilkS")
		)
		(fp_line
			(start -0.7874 0.4064)
			(end 0.7874 0.4064)
			(stroke
				(width 0.1524)
				(type default)
			)
			(layer "B.SilkS")
		)
		(fp_line
			(start -0.7874 -0.4064)
			(end -0.7874 0.4064)
			(stroke
				(width 0.1524)
				(type default)
			)
			(layer "B.SilkS")
		)
		(fp_line
			(start 0.67945 0.3048)
			(end 0.67945 -0.305054)
			(stroke
				(width 0.1)
				(type default)
			)
			(layer "B.Fab")
		)
		(fp_line
			(start 0.67945 -0.305054)
			(end 0.12065 -0.305054)
			(stroke
				(width 0.1)
				(type default)
			)
			(layer "B.Fab")
		)
		(fp_line
			(start 0.12065 0.3048)
			(end 0.67945 0.3048)
			(stroke
				(width 0.1)
				(type default)
			)
			(layer "B.Fab")
		)
		(fp_line
			(start 0.12065 0.2794)
			(end 0.12065 0.3048)
			(stroke
				(width 0.1)
				(type default)
			)
			(layer "B.Fab")
		)
		(fp_line
			(start 0.12065 -0.2794)
			(end -0.12065 -0.2794)
			(stroke
				(width 0.1)
				(type default)
			)
			(layer "B.Fab")
		)
		(fp_line
			(start 0.12065 -0.305054)
			(end 0.12065 -0.2794)
			(stroke
				(width 0.1)
				(type default)
			)
			(layer "B.Fab")
		)
		(fp_line
			(start -0.120396 0.3048)
			(end -0.120396 0.2794)
			(stroke
				(width 0.1)
				(type default)
			)
			(layer "B.Fab")
		)
		(fp_line
			(start -0.120396 0.2794)
			(end 0.12065 0.2794)
			(stroke
				(width 0.1)
				(type default)
			)
			(layer "B.Fab")
		)
		(fp_line
			(start -0.12065 -0.2794)
			(end -0.12065 -0.3048)
			(stroke
				(width 0.1)
				(type default)
			)
			(layer "B.Fab")
		)
		(fp_line
			(start -0.12065 -0.3048)
			(end -0.67945 -0.3048)
			(stroke
				(width 0.1)
				(type default)
			)
			(layer "B.Fab")
		)
		(fp_line
			(start -0.67945 0.3048)
			(end -0.120396 0.3048)
			(stroke
				(width 0.1)
				(type default)
			)
			(layer "B.Fab")
		)
		(fp_line
			(start -0.67945 -0.3048)
			(end -0.67945 0.3048)
			(stroke
				(width 0.1)
				(type default)
			)
			(layer "B.Fab")
		)
		(pad "1" smd circle
			(at 0.40005 0)
			(size 0 0)
			(layers "B.Cu" "B.Mask" "B.Paste")
			(net "PVDDIO_P1")
		)
		(pad "2" smd circle
			(at -0.40005 0)
			(size 0 0)
			(layers "B.Cu" "B.Mask" "B.Paste")
			(net "GND")
		)
	)
	(footprint ""
		(layer "B.Cu")
		(at 82.996024 -408.517344 90)
		(property "Reference" "C6684"
			(at 0 0 90)
			(layer "B.SilkS")
			(hide yes)
			(effects
				(font
					(size 1.27 1.27)
				)
				(justify mirror)
			)
		)
		(property "Value" ""
			(at 0 0 90)
			(layer "B.Fab")
			(effects
				(font
					(size 1.27 1.27)
				)
				(justify mirror)
			)
		)
		(duplicate_pad_numbers_are_jumpers no)
		(fp_line
			(start 0.299974 -0.150114)
			(end -0.299974 -0.150114)
			(stroke
				(width 0.1)
				(type default)
			)
			(layer "B.Fab")
		)
		(fp_line
			(start -0.299974 -0.150114)
			(end -0.299974 0.150114)
			(stroke
				(width 0.1)
				(type default)
			)
			(layer "B.Fab")
		)
		(fp_line
			(start 0.299974 0.150114)
			(end 0.299974 -0.150114)
			(stroke
				(width 0.1)
				(type default)
			)
			(layer "B.Fab")
		)
		(fp_line
			(start -0.299974 0.150114)
			(end 0.299974 0.150114)
			(stroke
				(width 0.1)
				(type default)
			)
			(layer "B.Fab")
		)
		(pad "1" smd rect
			(at 0.2667 0 270)
			(size 0.3048 0.381)
			(layers "B.Cu" "B.Mask" "B.Paste")
			(net "P5E_CPU1_P1_TX_BUF_C_DN<11>")
		)
		(pad "2" smd rect
			(at -0.2667 0 270)
			(size 0.3048 0.381)
			(layers "B.Cu" "B.Mask" "B.Paste")
			(net "P5E_CPU1_P1_TX_BUF_DN<11>")
		)
	)
	(footprint ""
		(layer "B.Cu")
		(at 288.180272 -192.660016 180)
		(property "Reference" "C146"
			(at 0 0 0)
			(layer "B.SilkS")
			(hide yes)
			(effects
				(font
					(size 1.27 1.27)
				)
				(justify mirror)
			)
		)
		(property "Value" ""
			(at 0 0 0)
			(layer "B.Fab")
			(effects
				(font
					(size 1.27 1.27)
				)
				(justify mirror)
			)
		)
		(duplicate_pad_numbers_are_jumpers no)
		(fp_line
			(start 1.524 0.762)
			(end 1.524 -0.762)
			(stroke
				(width 0.1524)
				(type default)
			)
			(layer "B.SilkS")
		)
		(fp_line
			(start 1.524 -0.762)
			(end -1.524 -0.762)
			(stroke
				(width 0.1524)
				(type default)
			)
			(layer "B.SilkS")
		)
		(fp_line
			(start -1.524 0.762)
			(end 1.524 0.762)
			(stroke
				(width 0.1524)
				(type default)
			)
			(layer "B.SilkS")
		)
		(fp_line
			(start -1.524 -0.762)
			(end -1.524 0.762)
			(stroke
				(width 0.1524)
				(type default)
			)
			(layer "B.SilkS")
		)
		(fp_line
			(start 1.1049 0.724916)
			(end -1.1049 0.724916)
			(stroke
				(width 0.1)
				(type default)
			)
			(layer "B.Fab")
		)
		(fp_line
			(start 1.1049 -0.724916)
			(end 1.1049 0.724916)
			(stroke
				(width 0.1)
				(type default)
			)
			(layer "B.Fab")
		)
		(fp_line
			(start -1.1049 0.724916)
			(end -1.1049 -0.724916)
			(stroke
				(width 0.1)
				(type default)
			)
			(layer "B.Fab")
		)
		(fp_line
			(start -1.1049 -0.724916)
			(end 1.1049 -0.724916)
			(stroke
				(width 0.1)
				(type default)
			)
			(layer "B.Fab")
		)
		(pad "1" smd rect
			(at 0.889 0 180)
			(size 1.016 1.27)
			(layers "B.Cu" "B.Mask" "B.Paste")
			(net "P12V_MEM_CPU0")
		)
		(pad "2" smd rect
			(at -0.889 0 180)
			(size 1.016 1.27)
			(layers "B.Cu" "B.Mask" "B.Paste")
			(net "GND")
		)
	)
)
